# TIMECARD (Time Appliance Project (Time Card)) — schematic netlist excerpt (pin names and nets, part order shuffled) for the footprints in the layout excerpt that follows; sources: Cadence DE-HDL packaged netlist, KiCad conversion of R4006-B0001-02_R01.brd

R15  RESISTOR  10KOHM 1%  pkg SMC_0402R_H016  page 27 : \1\ = XP12R0V ; \2\ = XP12R0V_A_FLTB
R297  RESISTOR  4.7KOHM 1%  pkg SMC_0402R_H016  page 18 : \1\ = R_SHT3X_RST_N ; \2\ = SG

(kicad_pcb
	(version 20260206)
	(generator "pcbnew")
	(generator_version "10.0")
	(general
		(thickness 1.6)
		(legacy_teardrops no)
	)
	(paper "A4")
	(title_block
		(title "timecard-production-celestica-r4006 — R4006-B0001-02_R01.brd")
		(comment 1 "Time Appliance Project (Time Card) / footprints 395-396 of 1113")
	)
	(layers
		(0 "F.Cu" signal "TOP")
		(4 "In1.Cu" signal "L02_GND1")
		(6 "In2.Cu" signal "L03_SIG1")
		(8 "In3.Cu" signal "L04_GND2")
		(10 "In4.Cu" signal "L05_VCC1")
		(12 "In5.Cu" signal "L06_VCC2")
		(14 "In6.Cu" signal "L07_GND3")
		(16 "In7.Cu" signal "L08_SIG2")
		(18 "In8.Cu" signal "L09_GND4")
		(2 "B.Cu" signal "BOTTOM")
		(9 "F.Adhes" user "F.Adhesive")
		(11 "B.Adhes" user "B.Adhesive")
		(13 "F.Paste" user "Package Geometry/Pastemask Top")
		(15 "B.Paste" user "Package Geometry/Pastemask Bottom")
		(5 "F.SilkS" user "Ref Des/Silkscreen Top")
		(7 "B.SilkS" user "Ref Des/Silkscreen Bottom")
		(1 "F.Mask" user "Board Geometry/Soldermask Top")
		(3 "B.Mask" user "Board Geometry/Soldermask Bottom")
		(17 "Dwgs.User" user "User.Drawings")
		(19 "Cmts.User" user "User.Comments")
		(21 "Eco1.User" user "User.Eco1")
		(23 "Eco2.User" user "User.Eco2")
		(25 "Edge.Cuts" user "Board Geometry/Outline")
		(27 "Margin" user)
		(31 "F.CrtYd" user "Package Geometry/Place Bound Top")
		(29 "B.CrtYd" user "Package Geometry/Place Bound Bottom")
		(35 "F.Fab" user "Ref Des/Assembly Top")
		(33 "B.Fab" user "Ref Des/Assembly Bottom")
	)
	(footprint ""
		(layer "F.Cu")
		(at 150.381462 -58.014108 180)
		(property "Reference" "R297"
			(at 1.410462 3.541522 0)
			(unlocked yes)
			(layer "F.SilkS")
			(effects
				(font
					(size 0.7874 0.5842)
					(thickness 0.1524)
				)
			)
		)
		(property "Value" "VAL*"
			(at 0.02032 2.13233 180)
			(unlocked yes)
			(layer "F.Fab")
			(hide yes)
			(effects
				(font
					(size 0.7874 0.5842)
					(thickness 0.1524)
				)
			)
		)
		(property "Tolerance" "TOL*"
			(at 0.044704 3.05435 180)
			(unlocked yes)
			(layer "Cmts.User")
			(hide yes)
			(effects
				(font
					(size 0.7874 0.5842)
					(thickness 0.1524)
				)
			)
		)
		(property "User Part Number" "PARTNUM*"
			(at 0.02032 4.024884 180)
			(unlocked yes)
			(layer "Cmts.User")
			(hide yes)
			(effects
				(font
					(size 0.7874 0.5842)
					(thickness 0.1524)
				)
			)
		)
		(property "Device Type" "RESISTOR-G155-14701-01,4.7KOHMA"
			(at 0.008382 1.210564 180)
			(unlocked yes)
			(layer "F.Fab")
			(hide yes)
			(effects
				(font
					(size 0.7874 0.5842)
					(thickness 0.1524)
				)
			)
		)
		(duplicate_pad_numbers_are_jumpers no)
		(fp_line
			(start 1.143 0.5588)
			(end 1.143 -0.5588)
			(stroke
				(width 0.1)
				(type default)
			)
			(layer "F.SilkS")
		)
		(fp_line
			(start 1.143 -0.5588)
			(end -1.143 -0.5588)
			(stroke
				(width 0.1)
				(type default)
			)
			(layer "F.SilkS")
		)
		(fp_line
			(start -1.143 0.5588)
			(end 1.143 0.5588)
			(stroke
				(width 0.1)
				(type default)
			)
			(layer "F.SilkS")
		)
		(fp_line
			(start -1.143 -0.5588)
			(end -1.143 0.5588)
			(stroke
				(width 0.1)
				(type default)
			)
			(layer "F.SilkS")
		)
		(fp_rect
			(start -1.143 0.5588)
			(end 1.143 -0.5588)
			(stroke
				(width 0)
				(type default)
			)
			(fill no)
			(layer "F.CrtYd")
		)
		(fp_line
			(start 0.508 0.3048)
			(end 0.508 -0.3048)
			(stroke
				(width 0.1)
				(type default)
			)
			(layer "F.Fab")
		)
		(fp_line
			(start 0.508 -0.3048)
			(end -0.508 -0.3048)
			(stroke
				(width 0.1)
				(type default)
			)
			(layer "F.Fab")
		)
		(fp_line
			(start -0.508 0.3048)
			(end 0.508 0.3048)
			(stroke
				(width 0.1)
				(type default)
			)
			(layer "F.Fab")
		)
		(fp_line
			(start -0.508 -0.3048)
			(end -0.508 0.3048)
			(stroke
				(width 0.1)
				(type default)
			)
			(layer "F.Fab")
		)
		(pad "1" smd rect
			(at -0.5334 0 180)
			(size 0.7112 0.6096)
			(layers "F.Cu" "F.Mask" "F.Paste")
			(net "R_SHT3X_RST_N")
		)
		(pad "2" smd rect
			(at 0.5334 0 180)
			(size 0.7112 0.6096)
			(layers "F.Cu" "F.Mask" "F.Paste")
			(net "SG")
		)
		(zone
			(layer "F.Cu")
			(hatch none 0.5)
			(connect_pads
				(clearance 0)
			)
			(min_thickness 0.25)
			(keepout
				(tracks allowed)
				(vias not_allowed)
				(pads allowed)
				(copperpour not_allowed)
				(footprints allowed)
			)
			(placement
				(enabled no)
				(sheetname "")
			)
			(fill
				(thermal_gap 0.5)
				(thermal_bridge_width 0.5)
				(island_removal_mode 0)
			)
			(polygon
				(pts
					(xy 150.457662 -58.318908) (xy 150.305262 -58.318908) (xy 150.305262 -57.709308) (xy 150.457662 -57.709308)
				)
			)
		)
	)
	(footprint ""
		(layer "F.Cu")
		(at 145.8214 -99.2378 180)
		(property "Reference" "R15"
			(at -3.0226 0.16383 0)
			(unlocked yes)
			(layer "F.SilkS")
			(effects
				(font
					(size 0.7874 0.5842)
					(thickness 0.1524)
				)
			)
		)
		(property "Value" "VAL*"
			(at 0.02032 2.13233 180)
			(unlocked yes)
			(layer "F.Fab")
			(hide yes)
			(effects
				(font
					(size 0.7874 0.5842)
					(thickness 0.1524)
				)
			)
		)
		(property "Device Type" "RESISTOR-G155-11002-01,10KOHM,A"
			(at 0.008382 1.210564 180)
			(unlocked yes)
			(layer "F.Fab")
			(hide yes)
			(effects
				(font
					(size 0.7874 0.5842)
					(thickness 0.1524)
				)
			)
		)
		(property "User Part Number" "PARTNUM*"
			(at 0.02032 4.024884 180)
			(unlocked yes)
			(layer "Cmts.User")
			(hide yes)
			(effects
				(font
					(size 0.7874 0.5842)
					(thickness 0.1524)
				)
			)
		)
		(property "Tolerance" "TOL*"
			(at 0.044704 3.05435 180)
			(unlocked yes)
			(layer "Cmts.User")
			(hide yes)
			(effects
				(font
					(size 0.7874 0.5842)
					(thickness 0.1524)
				)
			)
		)
		(duplicate_pad_numbers_are_jumpers no)
		(fp_line
			(start 1.143 0.5588)
			(end 1.143 -0.5588)
			(stroke
				(width 0.1)
				(type default)
			)
			(layer "F.SilkS")
		)
		(fp_line
			(start 1.143 -0.5588)
			(end -1.143 -0.5588)
			(stroke
				(width 0.1)
				(type default)
			)
			(layer "F.SilkS")
		)
		(fp_line
			(start -1.143 0.5588)
			(end 1.143 0.5588)
			(stroke
				(width 0.1)
				(type default)
			)
			(layer "F.SilkS")
		)
		(fp_line
			(start -1.143 -0.5588)
			(end -1.143 0.5588)
			(stroke
				(width 0.1)
				(type default)
			)
			(layer "F.SilkS")
		)
		(fp_rect
			(start 1.143 -0.5588)
			(end -1.143 0.5588)
			(stroke
				(width 0)
				(type default)
			)
			(fill no)
			(layer "F.CrtYd")
		)
		(fp_line
			(start 0.508 0.3048)
			(end 0.508 -0.3048)
			(stroke
				(width 0.1)
				(type default)
			)
			(layer "F.Fab")
		)
		(fp_line
			(start 0.508 -0.3048)
			(end -0.508 -0.3048)
			(stroke
				(width 0.1)
				(type default)
			)
			(layer "F.Fab")
		)
		(fp_line
			(start -0.508 0.3048)
			(end 0.508 0.3048)
			(stroke
				(width 0.1)
				(type default)
			)
			(layer "F.Fab")
		)
		(fp_line
			(start -0.508 -0.3048)
			(end -0.508 0.3048)
			(stroke
				(width 0.1)
				(type default)
			)
			(layer "F.Fab")
		)
		(pad "1" smd rect
			(at -0.5334 0 180)
			(size 0.7112 0.6096)
			(layers "F.Cu" "F.Mask" "F.Paste")
			(net "XP12R0V")
		)
		(pad "2" smd rect
			(at 0.5334 0 180)
			(size 0.7112 0.6096)
			(layers "F.Cu" "F.Mask" "F.Paste")
			(net "XP12R0V_A_FLTB")
		)
		(zone
			(layer "F.Cu")
			(hatch none 0.5)
			(connect_pads
				(clearance 0)
			)
			(min_thickness 0.25)
			(keepout
				(tracks allowed)
				(vias not_allowed)
				(pads allowed)
				(copperpour not_allowed)
				(footprints allowed)
			)
			(placement
				(enabled no)
				(sheetname "")
			)
			(fill
				(thermal_gap 0.5)
				(thermal_bridge_width 0.5)
				(island_removal_mode 0)
			)
			(polygon
				(pts
					(xy 145.7452 -98.933) (xy 145.8976 -98.933) (xy 145.8976 -99.5426) (xy 145.7452 -99.5426)
				)
			)
		)
	)
)
